# BASEBOARD_FAB2 (Tioga Pass) — schematic netlist excerpt (pin names and nets, part order shuffled) for the footprints in the layout excerpt that follows; sources: Cadence DE-HDL packaged netlist, KiCad conversion of Wiwynn_Tioga_Pass_MB.brd

R5N3  RES  10.0K 1% CHIP  pkg 0402  page 21 : A = P3V3_STBY ; B = FM_CPU0_PKGID2
C5G112  CAP_A  22.0UF 4V 20% X6S  pkg 0603V  page 243 : A = PVDDQ_KLM ; B = GND
R6L1  RES  1.00K 1% CHIP  pkg 0402  page 98 : A = M_F_VREF ; B = GND

(kicad_pcb
	(version 20260206)
	(generator "pcbnew")
	(generator_version "10.0")
	(general
		(thickness 1.6)
		(legacy_teardrops no)
	)
	(paper "A4")
	(title_block
		(title "Wiwynn_Tioga_Pass_MB.brd")
		(comment 1 "Tioga Pass / footprints 4246-4248 of 4770")
	)
	(layers
		(0 "F.Cu" signal "TOP")
		(4 "In1.Cu" signal "L2GND")
		(6 "In2.Cu" signal "L3")
		(8 "In3.Cu" signal "L4GND")
		(10 "In4.Cu" signal "L5")
		(12 "In5.Cu" signal "L6GND")
		(14 "In6.Cu" signal "L7VCC")
		(16 "In7.Cu" signal "L8VCC")
		(18 "In8.Cu" signal "L9GND")
		(20 "In9.Cu" signal "L10")
		(22 "In10.Cu" signal "L11GND")
		(24 "In11.Cu" signal "L12")
		(26 "In12.Cu" signal "L13GND")
		(2 "B.Cu" signal "BOTTOM")
		(9 "F.Adhes" user "F.Adhesive")
		(11 "B.Adhes" user "B.Adhesive")
		(13 "F.Paste" user "Package Geometry/Pastemask Top")
		(15 "B.Paste" user "Package Geometry/Pastemask Bottom")
		(5 "F.SilkS" user "Ref Des/Silkscreen Top")
		(7 "B.SilkS" user "Ref Des/Silkscreen Bottom")
		(1 "F.Mask" user "Board Geometry/Soldermask Top")
		(3 "B.Mask" user "Board Geometry/Soldermask Bottom")
		(17 "Dwgs.User" user "User.Drawings")
		(19 "Cmts.User" user "User.Comments")
		(21 "Eco1.User" user "User.Eco1")
		(23 "Eco2.User" user "User.Eco2")
		(25 "Edge.Cuts" user "Board Geometry/Outline")
		(27 "Margin" user)
		(31 "F.CrtYd" user "Package Geometry/Place Bound Top")
		(29 "B.CrtYd" user "Package Geometry/Place Bound Bottom")
		(35 "F.Fab" user "Ref Des/Assembly Top")
		(33 "B.Fab" user "Ref Des/Assembly Bottom")
	)
	(footprint ""
		(layer "B.Cu")
		(at 87.158068 -140.208 -90)
		(property "Reference" "C5G112"
			(at -1.14681 0.76708 0)
			(unlocked yes)
			(layer "B.SilkS")
			(effects
				(font
					(size 0.7874 0.5842)
					(thickness 0.1524)
				)
				(justify mirror)
			)
		)
		(property "Value" ""
			(at 0 0 90)
			(layer "B.Fab")
			(effects
				(font
					(size 1.27 1.27)
				)
				(justify mirror)
			)
		)
		(duplicate_pad_numbers_are_jumpers no)
		(fp_rect
			(start 0.4953 1.6002)
			(end -0.4953 -0.2032)
			(stroke
				(width 0)
				(type default)
			)
			(fill no)
			(layer "B.CrtYd")
		)
		(fp_line
			(start -0.4953 1.6002)
			(end 0.4953 1.6002)
			(stroke
				(width 0.1)
				(type default)
			)
			(layer "B.Fab")
		)
		(fp_line
			(start 0.4953 1.6002)
			(end 0.4953 -0.2032)
			(stroke
				(width 0.1)
				(type default)
			)
			(layer "B.Fab")
		)
		(fp_line
			(start -0.4953 -0.2032)
			(end -0.4953 1.6002)
			(stroke
				(width 0.1)
				(type default)
			)
			(layer "B.Fab")
		)
		(fp_line
			(start 0.4953 -0.2032)
			(end -0.4953 -0.2032)
			(stroke
				(width 0.1)
				(type default)
			)
			(layer "B.Fab")
		)
		(pad "1" smd rect
			(at 0 0 90)
			(size 0.762 0.889)
			(layers "B.Cu" "B.Mask" "B.Paste")
			(net "PVDDQ_KLM")
		)
		(pad "2" smd rect
			(at 0 1.397 90)
			(size 0.762 0.889)
			(layers "B.Cu" "B.Mask" "B.Paste")
			(net "GND")
		)
		(zone
			(layer "B.Cu")
			(hatch none 0.5)
			(connect_pads
				(clearance 0)
			)
			(min_thickness 0.25)
			(keepout
				(tracks not_allowed)
				(vias allowed)
				(pads allowed)
				(copperpour not_allowed)
				(footprints allowed)
			)
			(placement
				(enabled no)
				(sheetname "")
			)
			(fill
				(thermal_gap 0.5)
				(thermal_bridge_width 0.5)
				(island_removal_mode 0)
			)
			(polygon
				(pts
					(xy 86.205568 -139.827) (xy 86.713568 -139.827) (xy 86.713568 -140.589) (xy 86.205568 -140.589)
				)
			)
		)
	)
	(footprint ""
		(layer "B.Cu")
		(at 227.584 -91.821 90)
		(property "Reference" "R5N3"
			(at 0 0 90)
			(layer "B.SilkS")
			(hide yes)
			(effects
				(font
					(size 1.27 1.27)
				)
				(justify mirror)
			)
		)
		(property "Value" ""
			(at 0 0 90)
			(layer "B.Fab")
			(effects
				(font
					(size 1.27 1.27)
				)
				(justify mirror)
			)
		)
		(duplicate_pad_numbers_are_jumpers no)
		(fp_poly
			(pts
				(xy 0.2794 -0.1016) (xy -0.2794 -0.1016) (xy -0.2794 0.9906) (xy 0.2794 0.9906)
			)
			(stroke
				(width 0)
				(type default)
			)
			(fill no)
			(layer "B.CrtYd")
		)
		(fp_line
			(start 0.2794 -0.1016)
			(end 0.2794 0.9906)
			(stroke
				(width 0.1)
				(type default)
			)
			(layer "B.Fab")
		)
		(fp_line
			(start -0.2794 -0.1016)
			(end 0.2794 -0.1016)
			(stroke
				(width 0.1)
				(type default)
			)
			(layer "B.Fab")
		)
		(fp_line
			(start 0.2794 0.9906)
			(end -0.2794 0.9906)
			(stroke
				(width 0.1)
				(type default)
			)
			(layer "B.Fab")
		)
		(fp_line
			(start -0.2794 0.9906)
			(end -0.2794 -0.1016)
			(stroke
				(width 0.1)
				(type default)
			)
			(layer "B.Fab")
		)
		(pad "1" smd rect
			(at 0 0 270)
			(size 0.508 0.508)
			(layers "B.Cu" "B.Mask" "B.Paste")
			(net "P3V3_STBY")
		)
		(pad "2" smd rect
			(at 0 0.889 270)
			(size 0.508 0.508)
			(layers "B.Cu" "B.Mask" "B.Paste")
			(net "FM_CPU0_PKGID2")
		)
		(zone
			(layer "B.Cu")
			(hatch none 0.5)
			(connect_pads
				(clearance 0)
			)
			(min_thickness 0.25)
			(keepout
				(tracks allowed)
				(vias not_allowed)
				(pads allowed)
				(copperpour not_allowed)
				(footprints allowed)
			)
			(placement
				(enabled no)
				(sheetname "")
			)
			(fill
				(thermal_gap 0.5)
				(thermal_bridge_width 0.5)
				(island_removal_mode 0)
			)
			(polygon
				(pts
					(xy 227.838 -92.075) (xy 227.838 -91.567) (xy 228.219 -91.567) (xy 228.219 -92.075)
				)
			)
		)
		(zone
			(layer "B.Cu")
			(hatch none 0.5)
			(connect_pads
				(clearance 0)
			)
			(min_thickness 0.25)
			(keepout
				(tracks not_allowed)
				(vias allowed)
				(pads allowed)
				(copperpour not_allowed)
				(footprints allowed)
			)
			(placement
				(enabled no)
				(sheetname "")
			)
			(fill
				(thermal_gap 0.5)
				(thermal_bridge_width 0.5)
				(island_removal_mode 0)
			)
			(polygon
				(pts
					(xy 228.219 -92.075) (xy 228.219 -91.567) (xy 227.838 -91.567) (xy 227.838 -92.075)
				)
			)
		)
	)
	(footprint ""
		(layer "B.Cu")
		(at 194.564 -155.448)
		(property "Reference" "R6L1"
			(at 0 0 0)
			(layer "B.SilkS")
			(hide yes)
			(effects
				(font
					(size 1.27 1.27)
				)
				(justify mirror)
			)
		)
		(property "Value" ""
			(at 0 0 0)
			(layer "B.Fab")
			(effects
				(font
					(size 1.27 1.27)
				)
				(justify mirror)
			)
		)
		(duplicate_pad_numbers_are_jumpers no)
		(fp_poly
			(pts
				(xy 0.2794 -0.1016) (xy -0.2794 -0.1016) (xy -0.2794 0.9906) (xy 0.2794 0.9906)
			)
			(stroke
				(width 0)
				(type default)
			)
			(fill no)
			(layer "B.CrtYd")
		)
		(fp_line
			(start -0.2794 -0.1016)
			(end 0.2794 -0.1016)
			(stroke
				(width 0.1)
				(type default)
			)
			(layer "B.Fab")
		)
		(fp_line
			(start -0.2794 0.9906)
			(end -0.2794 -0.1016)
			(stroke
				(width 0.1)
				(type default)
			)
			(layer "B.Fab")
		)
		(fp_line
			(start 0.2794 -0.1016)
			(end 0.2794 0.9906)
			(stroke
				(width 0.1)
				(type default)
			)
			(layer "B.Fab")
		)
		(fp_line
			(start 0.2794 0.9906)
			(end -0.2794 0.9906)
			(stroke
				(width 0.1)
				(type default)
			)
			(layer "B.Fab")
		)
		(pad "1" smd rect
			(at 0 0 180)
			(size 0.508 0.508)
			(layers "B.Cu" "B.Mask" "B.Paste")
			(net "M_F_VREF")
		)
		(pad "2" smd rect
			(at 0 0.889 180)
			(size 0.508 0.508)
			(layers "B.Cu" "B.Mask" "B.Paste")
			(net "GND")
		)
		(zone
			(layer "B.Cu")
			(hatch none 0.5)
			(connect_pads
				(clearance 0)
			)
			(min_thickness 0.25)
			(keepout
				(tracks allowed)
				(vias not_allowed)
				(pads allowed)
				(copperpour not_allowed)
				(footprints allowed)
			)
			(placement
				(enabled no)
				(sheetname "")
			)
			(fill
				(thermal_gap 0.5)
				(thermal_bridge_width 0.5)
				(island_removal_mode 0)
			)
			(polygon
				(pts
					(xy 194.818 -155.194) (xy 194.31 -155.194) (xy 194.31 -154.813) (xy 194.818 -154.813)
				)
			)
		)
		(zone
			(layer "B.Cu")
			(hatch none 0.5)
			(connect_pads
				(clearance 0)
			)
			(min_thickness 0.25)
			(keepout
				(tracks not_allowed)
				(vias allowed)
				(pads allowed)
				(copperpour not_allowed)
				(footprints allowed)
			)
			(placement
				(enabled no)
				(sheetname "")
			)
			(fill
				(thermal_gap 0.5)
				(thermal_bridge_width 0.5)
				(island_removal_mode 0)
			)
			(polygon
				(pts
					(xy 194.818 -154.813) (xy 194.31 -154.813) (xy 194.31 -155.194) (xy 194.818 -155.194)
				)
			)
		)
	)
)
